# T6G (Grand Teton) — schematic netlist excerpt (pin names and nets, part order shuffled) for the footprints in the layout excerpt that follows; sources: Cadence DE-HDL packaged netlist, KiCad conversion of 04192023_DAF0TMB3IC0_F0TG_MB_C_brd_V02_OCP.brd

C6529  Q_CAP_DIFFBUS  DIFF BUS_0.22UF 6.3V 20% X6S  pkg C0201  page 275 : \1\ = P5E_CPU0_P0_TX_BUF_C_DP<14> ; \2\ = P5E_CPU0_P0_TX_BUF_DP<14>
PC2191  Q_CAP  0.068UF 16V 10% X7R  pkg 0402  page 262 : A = HSC_SS ; B = AGND_HSC
PC289_C0P1_4  Q_CAP  2.2UF 10V 10% X6S  pkg C0402  page 212 : A = PVDDCR_CPU0_P1_PVCC ; B = GND

(kicad_pcb
	(version 20260206)
	(generator "pcbnew")
	(generator_version "10.0")
	(general
		(thickness 1.6)
		(legacy_teardrops no)
	)
	(paper "A4")
	(title_block
		(title "04192023_DAF0TMB3IC0_F0TG_MB_C_brd_V02_OCP.brd")
		(comment 1 "Grand Teton / footprints 994-996 of 8354")
	)
	(layers
		(0 "F.Cu" signal "TOP")
		(4 "In1.Cu" signal "GND")
		(6 "In2.Cu" signal "IN1")
		(8 "In3.Cu" signal "GND1")
		(10 "In4.Cu" signal "IN2")
		(12 "In5.Cu" signal "GND2")
		(14 "In6.Cu" signal "IN3")
		(16 "In7.Cu" signal "GND3")
		(18 "In8.Cu" signal "VCC")
		(20 "In9.Cu" signal "VCC1")
		(22 "In10.Cu" signal "GND4")
		(24 "In11.Cu" signal "IN4")
		(26 "In12.Cu" signal "GND5")
		(28 "In13.Cu" signal "IN5")
		(30 "In14.Cu" signal "GND6")
		(32 "In15.Cu" signal "IN6")
		(34 "In16.Cu" signal "GND7")
		(2 "B.Cu" signal "BOTTOM")
		(9 "F.Adhes" user "F.Adhesive")
		(11 "B.Adhes" user "B.Adhesive")
		(13 "F.Paste" user "Package Geometry/Pastemask Top")
		(15 "B.Paste" user "Package Geometry/Pastemask Bottom")
		(5 "F.SilkS" user "Ref Des/Silkscreen Top")
		(7 "B.SilkS" user "Ref Des/Silkscreen Bottom")
		(1 "F.Mask" user "Board Geometry/Soldermask Top")
		(3 "B.Mask" user "Board Geometry/Soldermask Bottom")
		(17 "Dwgs.User" user "User.Drawings")
		(19 "Cmts.User" user "User.Comments")
		(21 "Eco1.User" user "User.Eco1")
		(23 "Eco2.User" user "User.Eco2")
		(25 "Edge.Cuts" user "Board Geometry/Outline")
		(27 "Margin" user)
		(31 "F.CrtYd" user "Package Geometry/Place Bound Top")
		(29 "B.CrtYd" user "Package Geometry/Place Bound Bottom")
		(35 "F.Fab" user "Ref Des/Assembly Top")
		(33 "B.Fab" user "Ref Des/Assembly Bottom")
	)
	(footprint ""
		(layer "F.Cu")
		(at 347.568266 -416.899344 -90)
		(property "Reference" "C6529"
			(at 0 0 270)
			(layer "F.SilkS")
			(hide yes)
			(effects
				(font
					(size 1.27 1.27)
				)
			)
		)
		(property "Value" ""
			(at 0 0 270)
			(layer "F.Fab")
			(effects
				(font
					(size 1.27 1.27)
				)
			)
		)
		(duplicate_pad_numbers_are_jumpers no)
		(fp_line
			(start -0.299974 0.150114)
			(end -0.299974 -0.150114)
			(stroke
				(width 0.1)
				(type default)
			)
			(layer "F.Fab")
		)
		(fp_line
			(start 0.299974 0.150114)
			(end -0.299974 0.150114)
			(stroke
				(width 0.1)
				(type default)
			)
			(layer "F.Fab")
		)
		(fp_line
			(start -0.299974 -0.150114)
			(end 0.299974 -0.150114)
			(stroke
				(width 0.1)
				(type default)
			)
			(layer "F.Fab")
		)
		(fp_line
			(start 0.299974 -0.150114)
			(end 0.299974 0.150114)
			(stroke
				(width 0.1)
				(type default)
			)
			(layer "F.Fab")
		)
		(pad "1" smd rect
			(at -0.2667 0 270)
			(size 0.3048 0.381)
			(layers "F.Cu" "F.Mask" "F.Paste")
			(net "P5E_CPU0_P0_TX_BUF_C_DP<14>")
		)
		(pad "2" smd rect
			(at 0.2667 0 270)
			(size 0.3048 0.381)
			(layers "F.Cu" "F.Mask" "F.Paste")
			(net "P5E_CPU0_P0_TX_BUF_DP<14>")
		)
	)
	(footprint ""
		(layer "F.Cu")
		(at 177.419 -404.495 90)
		(property "Reference" "PC2191"
			(at 0 0 90)
			(layer "F.SilkS")
			(hide yes)
			(effects
				(font
					(size 1.27 1.27)
				)
			)
		)
		(property "Value" ""
			(at 0 0 90)
			(layer "F.Fab")
			(effects
				(font
					(size 1.27 1.27)
				)
			)
		)
		(duplicate_pad_numbers_are_jumpers no)
		(fp_line
			(start 0.7874 -0.4064)
			(end 0.7874 0.4064)
			(stroke
				(width 0.1524)
				(type default)
			)
			(layer "F.SilkS")
		)
		(fp_line
			(start -0.7874 -0.4064)
			(end 0.7874 -0.4064)
			(stroke
				(width 0.1524)
				(type default)
			)
			(layer "F.SilkS")
		)
		(fp_line
			(start 0.7874 0.4064)
			(end -0.7874 0.4064)
			(stroke
				(width 0.1524)
				(type default)
			)
			(layer "F.SilkS")
		)
		(fp_line
			(start -0.7874 0.4064)
			(end -0.7874 -0.4064)
			(stroke
				(width 0.1524)
				(type default)
			)
			(layer "F.SilkS")
		)
		(fp_line
			(start -0.12065 -0.305054)
			(end -0.12065 -0.2794)
			(stroke
				(width 0.1)
				(type default)
			)
			(layer "F.Fab")
		)
		(fp_line
			(start -0.67945 -0.305054)
			(end -0.12065 -0.305054)
			(stroke
				(width 0.1)
				(type default)
			)
			(layer "F.Fab")
		)
		(fp_line
			(start 0.67945 -0.3048)
			(end 0.67945 0.3048)
			(stroke
				(width 0.1)
				(type default)
			)
			(layer "F.Fab")
		)
		(fp_line
			(start 0.12065 -0.3048)
			(end 0.67945 -0.3048)
			(stroke
				(width 0.1)
				(type default)
			)
			(layer "F.Fab")
		)
		(fp_line
			(start 0.12065 -0.2794)
			(end 0.12065 -0.3048)
			(stroke
				(width 0.1)
				(type default)
			)
			(layer "F.Fab")
		)
		(fp_line
			(start -0.12065 -0.2794)
			(end 0.12065 -0.2794)
			(stroke
				(width 0.1)
				(type default)
			)
			(layer "F.Fab")
		)
		(fp_line
			(start 0.120396 0.2794)
			(end -0.12065 0.2794)
			(stroke
				(width 0.1)
				(type default)
			)
			(layer "F.Fab")
		)
		(fp_line
			(start -0.12065 0.2794)
			(end -0.12065 0.3048)
			(stroke
				(width 0.1)
				(type default)
			)
			(layer "F.Fab")
		)
		(fp_line
			(start 0.67945 0.3048)
			(end 0.120396 0.3048)
			(stroke
				(width 0.1)
				(type default)
			)
			(layer "F.Fab")
		)
		(fp_line
			(start 0.120396 0.3048)
			(end 0.120396 0.2794)
			(stroke
				(width 0.1)
				(type default)
			)
			(layer "F.Fab")
		)
		(fp_line
			(start -0.12065 0.3048)
			(end -0.67945 0.3048)
			(stroke
				(width 0.1)
				(type default)
			)
			(layer "F.Fab")
		)
		(fp_line
			(start -0.67945 0.3048)
			(end -0.67945 -0.305054)
			(stroke
				(width 0.1)
				(type default)
			)
			(layer "F.Fab")
		)
		(pad "1" smd circle
			(at -0.40005 0 90)
			(size 0 0)
			(layers "F.Cu" "F.Mask" "F.Paste")
			(net "HSC_SS")
		)
		(pad "2" smd circle
			(at 0.40005 0 90)
			(size 0 0)
			(layers "F.Cu" "F.Mask" "F.Paste")
			(net "AGND_HSC")
		)
	)
	(footprint ""
		(layer "F.Cu")
		(at 111.13897 -178.173634 90)
		(property "Reference" "PC289_C0P1_4"
			(at 0 0 90)
			(layer "F.SilkS")
			(hide yes)
			(effects
				(font
					(size 1.27 1.27)
				)
			)
		)
		(property "Value" ""
			(at 0 0 90)
			(layer "F.Fab")
			(effects
				(font
					(size 1.27 1.27)
				)
			)
		)
		(duplicate_pad_numbers_are_jumpers no)
		(fp_line
			(start 0.7874 -0.4064)
			(end 0.7874 0.4064)
			(stroke
				(width 0.1524)
				(type default)
			)
			(layer "F.SilkS")
		)
		(fp_line
			(start -0.7874 -0.4064)
			(end 0.7874 -0.4064)
			(stroke
				(width 0.1524)
				(type default)
			)
			(layer "F.SilkS")
		)
		(fp_line
			(start 0.7874 0.4064)
			(end -0.7874 0.4064)
			(stroke
				(width 0.1524)
				(type default)
			)
			(layer "F.SilkS")
		)
		(fp_line
			(start -0.7874 0.4064)
			(end -0.7874 -0.4064)
			(stroke
				(width 0.1524)
				(type default)
			)
			(layer "F.SilkS")
		)
		(fp_line
			(start -0.12065 -0.305054)
			(end -0.12065 -0.2794)
			(stroke
				(width 0.1)
				(type default)
			)
			(layer "F.Fab")
		)
		(fp_line
			(start -0.67945 -0.305054)
			(end -0.12065 -0.305054)
			(stroke
				(width 0.1)
				(type default)
			)
			(layer "F.Fab")
		)
		(fp_line
			(start 0.67945 -0.3048)
			(end 0.67945 0.3048)
			(stroke
				(width 0.1)
				(type default)
			)
			(layer "F.Fab")
		)
		(fp_line
			(start 0.12065 -0.3048)
			(end 0.67945 -0.3048)
			(stroke
				(width 0.1)
				(type default)
			)
			(layer "F.Fab")
		)
		(fp_line
			(start 0.12065 -0.2794)
			(end 0.12065 -0.3048)
			(stroke
				(width 0.1)
				(type default)
			)
			(layer "F.Fab")
		)
		(fp_line
			(start -0.12065 -0.2794)
			(end 0.12065 -0.2794)
			(stroke
				(width 0.1)
				(type default)
			)
			(layer "F.Fab")
		)
		(fp_line
			(start 0.120396 0.2794)
			(end -0.12065 0.2794)
			(stroke
				(width 0.1)
				(type default)
			)
			(layer "F.Fab")
		)
		(fp_line
			(start -0.12065 0.2794)
			(end -0.12065 0.3048)
			(stroke
				(width 0.1)
				(type default)
			)
			(layer "F.Fab")
		)
		(fp_line
			(start 0.67945 0.3048)
			(end 0.120396 0.3048)
			(stroke
				(width 0.1)
				(type default)
			)
			(layer "F.Fab")
		)
		(fp_line
			(start 0.120396 0.3048)
			(end 0.120396 0.2794)
			(stroke
				(width 0.1)
				(type default)
			)
			(layer "F.Fab")
		)
		(fp_line
			(start -0.12065 0.3048)
			(end -0.67945 0.3048)
			(stroke
				(width 0.1)
				(type default)
			)
			(layer "F.Fab")
		)
		(fp_line
			(start -0.67945 0.3048)
			(end -0.67945 -0.305054)
			(stroke
				(width 0.1)
				(type default)
			)
			(layer "F.Fab")
		)
		(pad "1" smd circle
			(at -0.40005 0 90)
			(size 0 0)
			(layers "F.Cu" "F.Mask" "F.Paste")
			(net "PVDDCR_CPU0_P1_PVCC")
		)
		(pad "2" smd circle
			(at 0.40005 0 90)
			(size 0 0)
			(layers "F.Cu" "F.Mask" "F.Paste")
			(net "GND")
		)
	)
)
